(kicad_pcb
	(version 20241229)
	(generator "pcbnew")
	(generator_version "9.0")
	(general
		(thickness 1.6642)
		(legacy_teardrops no)
	)
	(paper "A3")
	(title_block
		(title "PolarFire SoM")
		(date "2025-07-22")
		(rev "1.1.4")
		(company "Antmicro Ltd")
		(comment 1 "www.antmicro.com")
		(comment 9 "footprints 141-144 of 470")
	)
	(layers
		(0 "F.Cu" mixed)
		(4 "In1.Cu" power)
		(6 "In2.Cu" signal)
		(8 "In3.Cu" power)
		(10 "In4.Cu" signal)
		(12 "In5.Cu" power)
		(14 "In6.Cu" power)
		(16 "In7.Cu" signal)
		(18 "In8.Cu" power)
		(20 "In9.Cu" signal)
		(22 "In10.Cu" power)
		(24 "In11.Cu" signal)
		(26 "In12.Cu" signal)
		(2 "B.Cu" mixed)
		(9 "F.Adhes" user "F.Adhesive")
		(11 "B.Adhes" user "B.Adhesive")
		(13 "F.Paste" user)
		(15 "B.Paste" user)
		(5 "F.SilkS" user "F.Silkscreen")
		(7 "B.SilkS" user "B.Silkscreen")
		(1 "F.Mask" user)
		(3 "B.Mask" user)
		(17 "Dwgs.User" user "User.Drawings")
		(19 "Cmts.User" user "User.Comments")
		(21 "Eco1.User" user "User.Eco1")
		(23 "Eco2.User" user "User.Eco2")
		(25 "Edge.Cuts" user)
		(27 "Margin" user)
		(31 "F.CrtYd" user "F.Courtyard")
		(29 "B.CrtYd" user "B.Courtyard")
		(35 "F.Fab" user)
		(33 "B.Fab" user)
	)
	(footprint "antmicro-footprints:C_0402_1005Metric"
		(layer "B.Cu")
		(at 197.04 138.614 90)
		(descr "Capacitor SMD 0402")
		(tags "capacitor SMD 0402")
		(property "Reference" "C33"
			(at 4.889 -9.715 90)
			(layer "B.SilkS")
			(effects
				(font
					(size 0.7 0.7)
					(thickness 0.15)
				)
				(justify right bottom mirror)
			)
		)
		(property "Value" "C_100n_0402"
			(at -1.022927 -2.155213 90)
			(layer "B.Fab")
			(hide yes)
			(effects
				(font
					(size 0.7 0.7)
					(thickness 0.15)
				)
				(justify right bottom mirror)
			)
		)
		(property "Datasheet" "https://www.murata.com/products/productdetail?partno=GRM155R61H104KE14%23"
			(at 0 0 90)
			(layer "F.Fab")
			(hide yes)
			(effects
				(font
					(size 1.27 1.27)
					(thickness 0.15)
				)
			)
		)
		(property "Description" "SMD Multilayer Ceramic Capacitor, 0.1 µF, 50 V, 0402 [1005 Metric], ± 10%, X5R, GRM Series"
			(at 0 0 90)
			(layer "F.Fab")
			(hide yes)
			(effects
				(font
					(size 1.27 1.27)
					(thickness 0.15)
				)
			)
		)
		(property "Author" "Antmicro"
			(at 335.654 -58.426 0)
			(layer "B.Fab")
			(hide yes)
			(effects
				(font
					(size 1 1)
					(thickness 0.15)
				)
				(justify mirror)
			)
		)
		(property "Dielectric" "X5R"
			(at 335.654 -58.426 0)
			(layer "B.Fab")
			(hide yes)
			(effects
				(font
					(size 1 1)
					(thickness 0.15)
				)
				(justify mirror)
			)
		)
		(property "License" "Apache-2.0"
			(at 335.654 -58.426 0)
			(layer "B.Fab")
			(hide yes)
			(effects
				(font
					(size 1 1)
					(thickness 0.15)
				)
				(justify mirror)
			)
		)
		(property "MPN" "GRM155R61H104KE14D"
			(at 335.654 -58.426 0)
			(layer "B.Fab")
			(hide yes)
			(effects
				(font
					(size 1 1)
					(thickness 0.15)
				)
				(justify mirror)
			)
		)
		(property "Manufacturer" "Murata"
			(at 335.654 -58.426 0)
			(layer "B.Fab")
			(hide yes)
			(effects
				(font
					(size 1 1)
					(thickness 0.15)
				)
				(justify mirror)
			)
		)
		(property "Public" ""
			(at 335.654 -58.426 0)
			(layer "B.Fab")
			(hide yes)
			(effects
				(font
					(size 1 1)
					(thickness 0.15)
				)
				(justify mirror)
			)
		)
		(property "Val" "100n"
			(at 335.654 -58.426 0)
			(layer "B.Fab")
			(hide yes)
			(effects
				(font
					(size 1 1)
					(thickness 0.15)
				)
				(justify mirror)
			)
		)
		(property "Voltage" "50V"
			(at 335.654 -58.426 0)
			(layer "B.Fab")
			(hide yes)
			(effects
				(font
					(size 1 1)
					(thickness 0.15)
				)
				(justify mirror)
			)
		)
		(sheetname "/FPGA Supply/")
		(sheetfile "fpga-supply.kicad_sch")
		(attr smd)
		(fp_rect
			(start -0.925 0.47)
			(end 0.925 -0.47)
			(stroke
				(width 0.05)
				(type default)
			)
			(fill no)
			(layer "B.CrtYd")
		)
		(fp_line
			(start 0.504 -0.248)
			(end -0.494 -0.248)
			(stroke
				(width 0.15)
				(type solid)
			)
			(layer "B.Fab")
		)
		(fp_line
			(start -0.494 -0.248)
			(end -0.494 0.25)
			(stroke
				(width 0.15)
				(type solid)
			)
			(layer "B.Fab")
		)
		(fp_line
			(start 0.504 0.25)
			(end 0.504 -0.248)
			(stroke
				(width 0.15)
				(type solid)
			)
			(layer "B.Fab")
		)
		(fp_line
			(start -0.494 0.25)
			(end 0.504 0.25)
			(stroke
				(width 0.15)
				(type solid)
			)
			(layer "B.Fab")
		)
		(fp_text user "License: Apache-2.0"
			(at -0.939 -5.799 270)
			(layer "B.Fab")
			(effects
				(font
					(size 0.7 0.7)
					(thickness 0.15)
				)
				(justify left bottom mirror)
			)
		)
		(fp_text user "Author: Antmicro"
			(at -0.939 -3.399 270)
			(layer "B.Fab")
			(effects
				(font
					(size 0.7 0.7)
					(thickness 0.15)
				)
				(justify left bottom mirror)
			)
		)
		(fp_text user "${REFERENCE}"
			(at -0.939 -4.599 270)
			(layer "B.Fab")
			(effects
				(font
					(size 0.7 0.7)
					(thickness 0.15)
				)
				(justify left bottom mirror)
			)
		)
		(pad "1" smd roundrect
			(at -0.48 0 90)
			(size 0.59 0.64)
			(layers "B.Cu" "B.Mask" "B.Paste")
			(roundrect_rratio 0.25)
			(net 417 "GND")
			(pintype "passive")
		)
		(pad "2" smd roundrect
			(at 0.48 0 90)
			(size 0.59 0.64)
			(layers "B.Cu" "B.Mask" "B.Paste")
			(roundrect_rratio 0.25)
			(net 418 "+2V5")
			(pintype "passive")
		)
	)
	(footprint "antmicro-footprints:C_0402_1005Metric"
		(layer "B.Cu")
		(at 212.19 131.06 180)
		(descr "Capacitor SMD 0402")
		(tags "capacitor SMD 0402")
		(property "Reference" "C70"
			(at -1.14 -1.27 0)
			(layer "B.SilkS")
			(effects
				(font
					(size 0.7 0.7)
					(thickness 0.15)
				)
				(justify left bottom mirror)
			)
		)
		(property "Value" "C_100n_0402"
			(at -1.022927 -2.155213 0)
			(layer "B.Fab")
			(hide yes)
			(effects
				(font
					(size 0.7 0.7)
					(thickness 0.15)
				)
				(justify left bottom mirror)
			)
		)
		(property "Datasheet" "https://www.murata.com/products/productdetail?partno=GRM155R61H104KE14%23"
			(at 0 0 180)
			(layer "F.Fab")
			(hide yes)
			(effects
				(font
					(size 1.27 1.27)
					(thickness 0.15)
				)
			)
		)
		(property "Description" "SMD Multilayer Ceramic Capacitor, 0.1 µF, 50 V, 0402 [1005 Metric], ± 10%, X5R, GRM Series"
			(at 0 0 180)
			(layer "F.Fab")
			(hide yes)
			(effects
				(font
					(size 1.27 1.27)
					(thickness 0.15)
				)
			)
		)
		(property "Author" "Antmicro"
			(at 424.38 262.12 0)
			(layer "B.Fab")
			(hide yes)
			(effects
				(font
					(size 1 1)
					(thickness 0.15)
				)
				(justify mirror)
			)
		)
		(property "Dielectric" "X5R"
			(at 424.38 262.12 0)
			(layer "B.Fab")
			(hide yes)
			(effects
				(font
					(size 1 1)
					(thickness 0.15)
				)
				(justify mirror)
			)
		)
		(property "License" "Apache-2.0"
			(at 424.38 262.12 0)
			(layer "B.Fab")
			(hide yes)
			(effects
				(font
					(size 1 1)
					(thickness 0.15)
				)
				(justify mirror)
			)
		)
		(property "MPN" "GRM155R61H104KE14D"
			(at 424.38 262.12 0)
			(layer "B.Fab")
			(hide yes)
			(effects
				(font
					(size 1 1)
					(thickness 0.15)
				)
				(justify mirror)
			)
		)
		(property "Manufacturer" "Murata"
			(at 424.38 262.12 0)
			(layer "B.Fab")
			(hide yes)
			(effects
				(font
					(size 1 1)
					(thickness 0.15)
				)
				(justify mirror)
			)
		)
		(property "Public" ""
			(at 424.38 262.12 0)
			(layer "B.Fab")
			(hide yes)
			(effects
				(font
					(size 1 1)
					(thickness 0.15)
				)
				(justify mirror)
			)
		)
		(property "Val" "100n"
			(at 424.38 262.12 0)
			(layer "B.Fab")
			(hide yes)
			(effects
				(font
					(size 1 1)
					(thickness 0.15)
				)
				(justify mirror)
			)
		)
		(property "Voltage" "50V"
			(at 424.38 262.12 0)
			(layer "B.Fab")
			(hide yes)
			(effects
				(font
					(size 1 1)
					(thickness 0.15)
				)
				(justify mirror)
			)
		)
		(sheetname "/Memory/")
		(sheetfile "memory.kicad_sch")
		(attr smd)
		(fp_rect
			(start -0.925 0.47)
			(end 0.925 -0.47)
			(stroke
				(width 0.05)
				(type default)
			)
			(fill no)
			(layer "B.CrtYd")
		)
		(fp_line
			(start 0.504 0.25)
			(end 0.504 -0.248)
			(stroke
				(width 0.15)
				(type solid)
			)
			(layer "B.Fab")
		)
		(fp_line
			(start 0.504 -0.248)
			(end -0.494 -0.248)
			(stroke
				(width 0.15)
				(type solid)
			)
			(layer "B.Fab")
		)
		(fp_line
			(start -0.494 0.25)
			(end 0.504 0.25)
			(stroke
				(width 0.15)
				(type solid)
			)
			(layer "B.Fab")
		)
		(fp_line
			(start -0.494 -0.248)
			(end -0.494 0.25)
			(stroke
				(width 0.15)
				(type solid)
			)
			(layer "B.Fab")
		)
		(fp_text user "Author: Antmicro"
			(at -0.939 -3.399 0)
			(layer "B.Fab")
			(effects
				(font
					(size 0.7 0.7)
					(thickness 0.15)
				)
				(justify left bottom mirror)
			)
		)
		(fp_text user "${REFERENCE}"
			(at -0.939 -4.599 0)
			(layer "B.Fab")
			(effects
				(font
					(size 0.7 0.7)
					(thickness 0.15)
				)
				(justify left bottom mirror)
			)
		)
		(fp_text user "License: Apache-2.0"
			(at -0.939 -5.799 0)
			(layer "B.Fab")
			(effects
				(font
					(size 0.7 0.7)
					(thickness 0.15)
				)
				(justify left bottom mirror)
			)
		)
		(pad "1" smd roundrect
			(at -0.48 0 180)
			(size 0.59 0.64)
			(layers "B.Cu" "B.Mask" "B.Paste")
			(roundrect_rratio 0.25)
			(net 417 "GND")
			(pintype "passive")
		)
		(pad "2" smd roundrect
			(at 0.48 0 180)
			(size 0.59 0.64)
			(layers "B.Cu" "B.Mask" "B.Paste")
			(roundrect_rratio 0.25)
			(net 52 "/Memory/eMMC_VDDI")
			(pintype "passive")
		)
	)
	(footprint "antmicro-footprints:R_0402_1005Metric"
		(layer "B.Cu")
		(at 185.75 120.85 90)
		(descr "Resistor SMD 0402")
		(tags "resistor SMD 0402")
		(property "Reference" "R43"
			(at 1.05 -1.5 270)
			(layer "B.SilkS")
			(effects
				(font
					(size 0.7 0.7)
					(thickness 0.15)
				)
				(justify left bottom mirror)
			)
		)
		(property "Value" "R_10k_0402"
			(at -1.011843 -1.772047 270)
			(layer "B.Fab")
			(hide yes)
			(effects
				(font
					(size 0.7 0.7)
					(thickness 0.15)
				)
				(justify left bottom mirror)
			)
		)
		(property "Datasheet" "https://www.bourns.com/docs/product-datasheets/cr.pdf"
			(at 0 0 90)
			(layer "F.Fab")
			(hide yes)
			(effects
				(font
					(size 1.27 1.27)
					(thickness 0.15)
				)
			)
		)
		(property "Description" "SMD Chip Resistor, 10 kohm, ± 1%, 62.5 mW, 0402 [1005 Metric], Thick Film, General Purpose"
			(at 0 0 90)
			(layer "F.Fab")
			(hide yes)
			(effects
				(font
					(size 1.27 1.27)
					(thickness 0.15)
				)
			)
		)
		(property "Author" "Antmicro"
			(at 306.6 -64.9 0)
			(layer "B.Fab")
			(hide yes)
			(effects
				(font
					(size 1 1)
					(thickness 0.15)
				)
				(justify mirror)
			)
		)
		(property "License" "Apache-2.0"
			(at 306.6 -64.9 0)
			(layer "B.Fab")
			(hide yes)
			(effects
				(font
					(size 1 1)
					(thickness 0.15)
				)
				(justify mirror)
			)
		)
		(property "MPN" "CR0402-FX-1002GLF"
			(at 306.6 -64.9 0)
			(layer "B.Fab")
			(hide yes)
			(effects
				(font
					(size 1 1)
					(thickness 0.15)
				)
				(justify mirror)
			)
		)
		(property "Manufacturer" "Bourns"
			(at 306.6 -64.9 0)
			(layer "B.Fab")
			(hide yes)
			(effects
				(font
					(size 1 1)
					(thickness 0.15)
				)
				(justify mirror)
			)
		)
		(property "Public" ""
			(at 306.6 -64.9 0)
			(layer "B.Fab")
			(hide yes)
			(effects
				(font
					(size 1 1)
					(thickness 0.15)
				)
				(justify mirror)
			)
		)
		(property "Tolerance" "1%"
			(at 306.6 -64.9 0)
			(layer "B.Fab")
			(hide yes)
			(effects
				(font
					(size 1 1)
					(thickness 0.15)
				)
				(justify mirror)
			)
		)
		(property "Val" "10k"
			(at 306.6 -64.9 0)
			(layer "B.Fab")
			(hide yes)
			(effects
				(font
					(size 1 1)
					(thickness 0.15)
				)
				(justify mirror)
			)
		)
		(sheetname "/FPGA Config/")
		(sheetfile "fpga-config.kicad_sch")
		(attr smd)
		(fp_rect
			(start -0.925 0.47)
			(end 0.925 -0.47)
			(stroke
				(width 0.05)
				(type default)
			)
			(fill no)
			(layer "B.CrtYd")
		)
		(fp_rect
			(start -0.5 0.25)
			(end 0.5 -0.25)
			(stroke
				(width 0.15)
				(type solid)
			)
			(fill no)
			(layer "B.Fab")
		)
		(fp_text user "License: Apache-2.0"
			(at -0.95 -5.169 270)
			(layer "B.Fab")
			(effects
				(font
					(size 0.7 0.7)
					(thickness 0.15)
				)
				(justify left bottom mirror)
			)
		)
		(fp_text user "${REFERENCE}"
			(at -0.95 -3.168 270)
			(layer "B.Fab")
			(effects
				(font
					(size 0.7 0.7)
					(thickness 0.15)
				)
				(justify left bottom mirror)
			)
		)
		(fp_text user "Author: Antmicro"
			(at -0.95 -4.169 270)
			(layer "B.Fab")
			(effects
				(font
					(size 0.7 0.7)
					(thickness 0.15)
				)
				(justify left bottom mirror)
			)
		)
		(pad "1" smd roundrect
			(at -0.48 0 90)
			(size 0.59 0.64)
			(layers "B.Cu" "B.Mask" "B.Paste")
			(roundrect_rratio 0.25)
			(net 417 "GND")
			(pintype "passive")
		)
		(pad "2" smd roundrect
			(at 0.48 0 90)
			(size 0.59 0.64)
			(layers "B.Cu" "B.Mask" "B.Paste")
			(roundrect_rratio 0.25)
			(net 124 "JTAG_TCK")
			(pintype "passive")
		)
	)
	(footprint "antmicro-footprints:C_0402_1005Metric"
		(layer "B.Cu")
		(at 199.89 134.73 90)
		(descr "Capacitor SMD 0402")
		(tags "capacitor SMD 0402")
		(property "Reference" "C63"
			(at 5.48 -9.615 90)
			(layer "B.SilkS")
			(effects
				(font
					(size 0.7 0.7)
					(thickness 0.15)
				)
				(justify right bottom mirror)
			)
		)
		(property "Value" "C_100n_0402"
			(at -1.022927 -2.155213 90)
			(layer "B.Fab")
			(hide yes)
			(effects
				(font
					(size 0.7 0.7)
					(thickness 0.15)
				)
				(justify right bottom mirror)
			)
		)
		(property "Datasheet" "https://www.murata.com/products/productdetail?partno=GRM155R61H104KE14%23"
			(at 0 0 90)
			(layer "F.Fab")
			(hide yes)
			(effects
				(font
					(size 1.27 1.27)
					(thickness 0.15)
				)
			)
		)
		(property "Description" "SMD Multilayer Ceramic Capacitor, 0.1 µF, 50 V, 0402 [1005 Metric], ± 10%, X5R, GRM Series"
			(at 0 0 90)
			(layer "F.Fab")
			(hide yes)
			(effects
				(font
					(size 1.27 1.27)
					(thickness 0.15)
				)
			)
		)
		(property "Author" "Antmicro"
			(at 334.62 -65.16 0)
			(layer "B.Fab")
			(hide yes)
			(effects
				(font
					(size 1 1)
					(thickness 0.15)
				)
				(justify mirror)
			)
		)
		(property "Dielectric" "X5R"
			(at 334.62 -65.16 0)
			(layer "B.Fab")
			(hide yes)
			(effects
				(font
					(size 1 1)
					(thickness 0.15)
				)
				(justify mirror)
			)
		)
		(property "License" "Apache-2.0"
			(at 334.62 -65.16 0)
			(layer "B.Fab")
			(hide yes)
			(effects
				(font
					(size 1 1)
					(thickness 0.15)
				)
				(justify mirror)
			)
		)
		(property "MPN" "GRM155R61H104KE14D"
			(at 334.62 -65.16 0)
			(layer "B.Fab")
			(hide yes)
			(effects
				(font
					(size 1 1)
					(thickness 0.15)
				)
				(justify mirror)
			)
		)
		(property "Manufacturer" "Murata"
			(at 334.62 -65.16 0)
			(layer "B.Fab")
			(hide yes)
			(effects
				(font
					(size 1 1)
					(thickness 0.15)
				)
				(justify mirror)
			)
		)
		(property "Public" ""
			(at 334.62 -65.16 0)
			(layer "B.Fab")
			(hide yes)
			(effects
				(font
					(size 1 1)
					(thickness 0.15)
				)
				(justify mirror)
			)
		)
		(property "Val" "100n"
			(at 334.62 -65.16 0)
			(layer "B.Fab")
			(hide yes)
			(effects
				(font
					(size 1 1)
					(thickness 0.15)
				)
				(justify mirror)
			)
		)
		(property "Voltage" "50V"
			(at 334.62 -65.16 0)
			(layer "B.Fab")
			(hide yes)
			(effects
				(font
					(size 1 1)
					(thickness 0.15)
				)
				(justify mirror)
			)
		)
		(sheetname "/FPGA Supply/")
		(sheetfile "fpga-supply.kicad_sch")
		(attr smd)
		(fp_rect
			(start -0.925 0.47)
			(end 0.925 -0.47)
			(stroke
				(width 0.05)
				(type default)
			)
			(fill no)
			(layer "B.CrtYd")
		)
		(fp_line
			(start 0.504 -0.248)
			(end -0.494 -0.248)
			(stroke
				(width 0.15)
				(type solid)
			)
			(layer "B.Fab")
		)
		(fp_line
			(start -0.494 -0.248)
			(end -0.494 0.25)
			(stroke
				(width 0.15)
				(type solid)
			)
			(layer "B.Fab")
		)
		(fp_line
			(start 0.504 0.25)
			(end 0.504 -0.248)
			(stroke
				(width 0.15)
				(type solid)
			)
			(layer "B.Fab")
		)
		(fp_line
			(start -0.494 0.25)
			(end 0.504 0.25)
			(stroke
				(width 0.15)
				(type solid)
			)
			(layer "B.Fab")
		)
		(fp_text user "${REFERENCE}"
			(at -0.939 -4.599 270)
			(layer "B.Fab")
			(effects
				(font
					(size 0.7 0.7)
					(thickness 0.15)
				)
				(justify left bottom mirror)
			)
		)
		(fp_text user "License: Apache-2.0"
			(at -0.939 -5.799 270)
			(layer "B.Fab")
			(effects
				(font
					(size 0.7 0.7)
					(thickness 0.15)
				)
				(justify left bottom mirror)
			)
		)
		(fp_text user "Author: Antmicro"
			(at -0.939 -3.399 270)
			(layer "B.Fab")
			(effects
				(font
					(size 0.7 0.7)
					(thickness 0.15)
				)
				(justify left bottom mirror)
			)
		)
		(pad "1" smd roundrect
			(at -0.48 0 90)
			(size 0.59 0.64)
			(layers "B.Cu" "B.Mask" "B.Paste")
			(roundrect_rratio 0.25)
			(net 417 "GND")
			(pintype "passive")
		)
		(pad "2" smd roundrect
			(at 0.48 0 90)
			(size 0.59 0.64)
			(layers "B.Cu" "B.Mask" "B.Paste")
			(roundrect_rratio 0.25)
			(net 49 "VDDAUX")
			(pintype "passive")
		)
	)
)
